(kicad_pcb
	(version 20260206)
	(generator "pcbnew")
	(generator_version "10.0")
	(general
		(thickness 1.6)
		(legacy_teardrops no)
	)
	(paper "A4")
	(title_block
		(title "Bryce Canyon_R.DPB_16317-1_OCP.brd")
		(comment 1 "Bryce Canyon / footprints 662-668 of 2099")
	)
	(layers
		(0 "F.Cu" signal "TOP")
		(4 "In1.Cu" signal "L2GND")
		(6 "In2.Cu" signal "L3")
		(8 "In3.Cu" signal "L4VCC")
		(10 "In4.Cu" signal "L5VCC")
		(12 "In5.Cu" signal "L6")
		(14 "In6.Cu" signal "L7GND")
		(2 "B.Cu" signal "BOTTOM")
		(9 "F.Adhes" user "F.Adhesive")
		(11 "B.Adhes" user "B.Adhesive")
		(13 "F.Paste" user "Package Geometry/Pastemask Top")
		(15 "B.Paste" user "Package Geometry/Pastemask Bottom")
		(5 "F.SilkS" user "Ref Des/Silkscreen Top")
		(7 "B.SilkS" user "Ref Des/Silkscreen Bottom")
		(1 "F.Mask" user "Board Geometry/Soldermask Top")
		(3 "B.Mask" user "Board Geometry/Soldermask Bottom")
		(17 "Dwgs.User" user "User.Drawings")
		(19 "Cmts.User" user "User.Comments")
		(21 "Eco1.User" user "User.Eco1")
		(23 "Eco2.User" user "User.Eco2")
		(25 "Edge.Cuts" user "Board Geometry/Outline")
		(27 "Margin" user)
		(31 "F.CrtYd" user "Package Geometry/Place Bound Top")
		(29 "B.CrtYd" user "Package Geometry/Place Bound Bottom")
		(35 "F.Fab" user "Ref Des/Assembly Top")
		(33 "B.Fab" user "Ref Des/Assembly Bottom")
	)
	(footprint ""
		(layer "F.Cu")
		(at 459.613 -274.955 180)
		(property "Reference" "C165"
			(at 0 0 180)
			(layer "F.SilkS")
			(hide yes)
			(effects
				(font
					(size 1.27 1.27)
				)
			)
		)
		(property "Value" "SC4D7U25V5KX-1-GP"
			(at -0.0762 -6.1214 180)
			(unlocked yes)
			(layer "F.Fab")
			(hide yes)
			(effects
				(font
					(size 1.016 1.016)
					(thickness 0.1524)
				)
			)
		)
		(property "Device Type" "C805H58"
			(at -0.0762 -8.1534 180)
			(unlocked yes)
			(layer "F.Fab")
			(hide yes)
			(effects
				(font
					(size 1.016 1.016)
					(thickness 0.1524)
				)
			)
		)
		(duplicate_pad_numbers_are_jumpers no)
		(fp_line
			(start 0.635 0)
			(end -0.635 0)
			(stroke
				(width 0.508)
				(type default)
			)
			(layer "F.SilkS")
		)
		(fp_rect
			(start -0.9652 1.778)
			(end 0.9652 -1.778)
			(stroke
				(width 0)
				(type default)
			)
			(fill no)
			(layer "F.CrtYd")
		)
		(fp_poly
			(pts
				(xy -0.9652 -1.778) (xy 0.9652 -1.778) (xy 0.9652 1.778) (xy -0.9652 1.778)
			)
			(stroke
				(width 0)
				(type default)
			)
			(fill no)
			(layer "F.Fab")
		)
		(pad "1" smd rect
			(at 0 -0.9652 180)
			(size 1.397 1.143)
			(layers "F.Cu" "F.Mask" "F.Paste")
			(net "P12V_HDD10")
		)
		(pad "2" smd rect
			(at 0 0.9652 180)
			(size 1.397 1.143)
			(layers "F.Cu" "F.Mask" "F.Paste")
			(net "GND")
		)
	)
	(footprint ""
		(layer "F.Cu")
		(at 283.41955 -157.541722)
		(property "Reference" "R490"
			(at 0 0 0)
			(layer "F.SilkS")
			(hide yes)
			(effects
				(font
					(size 1.27 1.27)
				)
			)
		)
		(property "Value" "0R2J-2-GP"
			(at 0.064008 -3.993896 0)
			(unlocked yes)
			(layer "F.Fab")
			(hide yes)
			(effects
				(font
					(size 1.016 1.016)
					(thickness 0.1524)
				)
			)
		)
		(property "Device Type" "R402H16"
			(at 0.064008 -5.517896 0)
			(unlocked yes)
			(layer "F.Fab")
			(hide yes)
			(effects
				(font
					(size 1.016 1.016)
					(thickness 0.1524)
				)
			)
		)
		(duplicate_pad_numbers_are_jumpers no)
		(fp_line
			(start -0.508 -0.9398)
			(end -0.508 0.9398)
			(stroke
				(width 0.1524)
				(type default)
			)
			(layer "F.SilkS")
		)
		(fp_line
			(start 0.508 -0.9398)
			(end -0.508 -0.9398)
			(stroke
				(width 0.1524)
				(type default)
			)
			(layer "F.SilkS")
		)
		(fp_rect
			(start -0.508 0.9398)
			(end 0.508 -0.9398)
			(stroke
				(width 0)
				(type default)
			)
			(fill no)
			(layer "F.CrtYd")
		)
		(fp_rect
			(start -0.508 0.9398)
			(end 0.508 -0.9398)
			(stroke
				(width 0)
				(type default)
			)
			(fill no)
			(layer "F.Fab")
		)
		(pad "1" smd custom
			(at 0 -0.4445)
			(size 0.1397 0.1397)
			(layers "F.Cu" "F.Mask" "F.Paste")
			(net "SCC_B_HS_EN")
			(options
				(clearance outline)
				(anchor circle)
			)
			(primitives
				(gr_poly
					(pts
						(arc
							(start -0.1778 -0.2794)
							(mid -0.249642 -0.249642)
							(end -0.2794 -0.1778)
						)
						(arc
							(start -0.2794 0.1778)
							(mid -0.249642 0.249642)
							(end -0.1778 0.2794)
						)
						(arc
							(start 0.1778 0.2794)
							(mid 0.249642 0.249642)
							(end 0.2794 0.1778)
						)
						(arc
							(start 0.2794 -0.1778)
							(mid 0.249642 -0.249642)
							(end 0.1778 -0.2794)
						)
					)
					(width 0)
					(fill yes)
				)
			)
		)
		(pad "2" smd custom
			(at 0 0.4445)
			(size 0.1397 0.1397)
			(layers "F.Cu" "F.Mask" "F.Paste")
			(net "GND")
			(options
				(clearance outline)
				(anchor circle)
			)
			(primitives
				(gr_poly
					(pts
						(arc
							(start -0.1778 -0.2794)
							(mid -0.249642 -0.249642)
							(end -0.2794 -0.1778)
						)
						(arc
							(start -0.2794 0.1778)
							(mid -0.249642 0.249642)
							(end -0.1778 0.2794)
						)
						(arc
							(start 0.1778 0.2794)
							(mid 0.249642 0.249642)
							(end 0.2794 0.1778)
						)
						(arc
							(start 0.2794 -0.1778)
							(mid 0.249642 -0.249642)
							(end 0.1778 -0.2794)
						)
					)
					(width 0)
					(fill yes)
				)
			)
		)
	)
	(footprint ""
		(layer "F.Cu")
		(at 319.216024 -39.705026)
		(property "Reference" "TP171"
			(at 0 0 0)
			(layer "F.SilkS")
			(hide yes)
			(effects
				(font
					(size 1.27 1.27)
				)
			)
		)
		(property "Value" "*"
			(at -0.0508 -1.6764 0)
			(unlocked yes)
			(layer "F.Fab")
			(hide yes)
			(effects
				(font
					(size 1.016 1.016)
					(thickness 0.1524)
				)
			)
		)
		(property "Device Type" "TPAD32"
			(at -0.0508 -3.2004 0)
			(unlocked yes)
			(layer "F.Fab")
			(hide yes)
			(effects
				(font
					(size 1.016 1.016)
					(thickness 0.1524)
				)
			)
		)
		(duplicate_pad_numbers_are_jumpers no)
		(fp_poly
			(pts
				(arc
					(start 0.4064 0)
					(mid -0.4064 0)
					(end 0.4064 0)
				)
			)
			(stroke
				(width 0)
				(type default)
			)
			(fill no)
			(layer "F.CrtYd")
		)
		(fp_poly
			(pts
				(arc
					(start 0.7112 0)
					(mid -0.7112 0)
					(end 0.7112 0)
				)
			)
			(stroke
				(width 0)
				(type default)
			)
			(fill no)
			(layer "F.Fab")
		)
		(pad "1" smd circle
			(at 0 0)
			(size 0.8128 0.8128)
			(layers "F.Cu" "F.Mask" "F.Paste")
			(net "ACT_HDD_30")
		)
	)
	(footprint ""
		(layer "F.Cu")
		(at 315.149992 -180.399944)
		(property "Reference" "LED7"
			(at 0 0 0)
			(layer "F.SilkS")
			(hide yes)
			(effects
				(font
					(size 1.27 1.27)
				)
			)
		)
		(property "Value" "LED-BY-19-GP"
			(at -2.132076 1.414018 0)
			(unlocked yes)
			(layer "F.Fab")
			(hide yes)
			(effects
				(font
					(size 1.016 1.016)
					(thickness 0.1524)
				)
			)
		)
		(property "Device Type" "LED-1615-4PH26"
			(at -2.132076 -0.109982 0)
			(unlocked yes)
			(layer "F.Fab")
			(hide yes)
			(effects
				(font
					(size 1.016 1.016)
					(thickness 0.1524)
				)
			)
		)
		(duplicate_pad_numbers_are_jumpers no)
		(fp_line
			(start -1.2954 0.254)
			(end -1.2954 1.6002)
			(stroke
				(width 0.508)
				(type default)
			)
			(layer "F.SilkS")
		)
		(fp_line
			(start -1.2954 1.6002)
			(end 1.2954 1.6002)
			(stroke
				(width 0.508)
				(type default)
			)
			(layer "F.SilkS")
		)
		(fp_line
			(start -1.1176 -1.4224)
			(end 1.1176 -1.4224)
			(stroke
				(width 0.1524)
				(type default)
			)
			(layer "F.SilkS")
		)
		(fp_line
			(start -1.1176 1.4224)
			(end -1.1176 -1.4224)
			(stroke
				(width 0.1524)
				(type default)
			)
			(layer "F.SilkS")
		)
		(fp_line
			(start 1.1176 -1.4224)
			(end 1.1176 1.4224)
			(stroke
				(width 0.1524)
				(type default)
			)
			(layer "F.SilkS")
		)
		(fp_line
			(start 1.1176 1.4224)
			(end -1.1176 1.4224)
			(stroke
				(width 0.1524)
				(type default)
			)
			(layer "F.SilkS")
		)
		(fp_line
			(start 1.2954 1.6002)
			(end 1.2954 0.254)
			(stroke
				(width 0.508)
				(type default)
			)
			(layer "F.SilkS")
		)
		(fp_rect
			(start -0.7493 0.8001)
			(end 0.7493 -0.8001)
			(stroke
				(width 0)
				(type default)
			)
			(fill no)
			(layer "F.CrtYd")
		)
		(fp_poly
			(pts
				(xy -1.3716 1.6764) (xy -1.3716 -1.6764) (xy 1.3716 -1.6764) (xy 1.3716 0.0635) (xy 0.7493 0.0635)
				(xy 0.7493 -0.8001) (xy -0.7493 -0.8001) (xy -0.7493 0.8001) (xy 0.7493 0.8001) (xy 0.7493 0.0762)
				(xy 1.3716 0.0762) (xy 1.3716 1.6764)
			)
			(stroke
				(width 0)
				(type default)
			)
			(fill no)
			(layer "F.CrtYd")
		)
		(fp_rect
			(start -1.3716 1.6764)
			(end 1.3716 -1.6764)
			(stroke
				(width 0)
				(type default)
			)
			(fill no)
			(layer "F.Fab")
		)
		(pad "1" smd rect
			(at 0.50038 -0.73025)
			(size 0.7112 0.8636)
			(layers "F.Cu" "F.Mask" "F.Paste")
			(net "DRV_ACT_6")
		)
		(pad "2" smd rect
			(at -0.50038 -0.73025)
			(size 0.7112 0.8636)
			(layers "F.Cu" "F.Mask" "F.Paste")
			(net "FLT_HDD6")
		)
		(pad "3" smd rect
			(at 0.50038 0.73025)
			(size 0.7112 0.8636)
			(layers "F.Cu" "F.Mask" "F.Paste")
			(net "DRV_ACT_6_N")
		)
		(pad "4" smd rect
			(at -0.50038 0.73025)
			(size 0.7112 0.8636)
			(layers "F.Cu" "F.Mask" "F.Paste")
			(net "FLT_HDD6_N")
		)
	)
	(footprint ""
		(layer "F.Cu")
		(at 395.224 -128.651)
		(property "Reference" "R542"
			(at 0 0 0)
			(layer "F.SilkS")
			(hide yes)
			(effects
				(font
					(size 1.27 1.27)
				)
			)
		)
		(property "Value" "4K7R2F-GP"
			(at 0.064008 -3.993896 0)
			(unlocked yes)
			(layer "F.Fab")
			(hide yes)
			(effects
				(font
					(size 1.016 1.016)
					(thickness 0.1524)
				)
			)
		)
		(property "Device Type" "R402H16"
			(at 0.064008 -5.517896 0)
			(unlocked yes)
			(layer "F.Fab")
			(hide yes)
			(effects
				(font
					(size 1.016 1.016)
					(thickness 0.1524)
				)
			)
		)
		(duplicate_pad_numbers_are_jumpers no)
		(fp_line
			(start -0.508 -0.9398)
			(end -0.508 0.9398)
			(stroke
				(width 0.1524)
				(type default)
			)
			(layer "F.SilkS")
		)
		(fp_line
			(start 0.508 -0.9398)
			(end -0.508 -0.9398)
			(stroke
				(width 0.1524)
				(type default)
			)
			(layer "F.SilkS")
		)
		(fp_rect
			(start -0.508 0.9398)
			(end 0.508 -0.9398)
			(stroke
				(width 0)
				(type default)
			)
			(fill no)
			(layer "F.CrtYd")
		)
		(fp_rect
			(start -0.508 0.9398)
			(end 0.508 -0.9398)
			(stroke
				(width 0)
				(type default)
			)
			(fill no)
			(layer "F.Fab")
		)
		(pad "1" smd custom
			(at 0 -0.4445)
			(size 0.1397 0.1397)
			(layers "F.Cu" "F.Mask" "F.Paste")
			(net "SW_PWR_R_HDD20")
			(options
				(clearance outline)
				(anchor circle)
			)
			(primitives
				(gr_poly
					(pts
						(arc
							(start -0.1778 -0.2794)
							(mid -0.249642 -0.249642)
							(end -0.2794 -0.1778)
						)
						(arc
							(start -0.2794 0.1778)
							(mid -0.249642 0.249642)
							(end -0.1778 0.2794)
						)
						(arc
							(start 0.1778 0.2794)
							(mid 0.249642 0.249642)
							(end 0.2794 0.1778)
						)
						(arc
							(start 0.2794 -0.1778)
							(mid 0.249642 -0.249642)
							(end 0.1778 -0.2794)
						)
					)
					(width 0)
					(fill yes)
				)
			)
		)
		(pad "2" smd custom
			(at 0 0.4445)
			(size 0.1397 0.1397)
			(layers "F.Cu" "F.Mask" "F.Paste")
			(net "GND")
			(options
				(clearance outline)
				(anchor circle)
			)
			(primitives
				(gr_poly
					(pts
						(arc
							(start -0.1778 -0.2794)
							(mid -0.249642 -0.249642)
							(end -0.2794 -0.1778)
						)
						(arc
							(start -0.2794 0.1778)
							(mid -0.249642 0.249642)
							(end -0.1778 0.2794)
						)
						(arc
							(start 0.1778 0.2794)
							(mid 0.249642 0.249642)
							(end 0.2794 0.1778)
						)
						(arc
							(start 0.2794 -0.1778)
							(mid 0.249642 -0.249642)
							(end 0.1778 -0.2794)
						)
					)
					(width 0)
					(fill yes)
				)
			)
		)
	)
	(footprint ""
		(layer "F.Cu")
		(at 45.814996 -360.299)
		(property "Reference" "R963"
			(at 0 0 0)
			(layer "F.SilkS")
			(hide yes)
			(effects
				(font
					(size 1.27 1.27)
				)
			)
		)
		(property "Value" "4K7R2J-2-GP"
			(at 0.064008 -3.993896 0)
			(unlocked yes)
			(layer "F.Fab")
			(hide yes)
			(effects
				(font
					(size 1.016 1.016)
					(thickness 0.1524)
				)
			)
		)
		(property "Device Type" "R402H16"
			(at 0.064008 -5.517896 0)
			(unlocked yes)
			(layer "F.Fab")
			(hide yes)
			(effects
				(font
					(size 1.016 1.016)
					(thickness 0.1524)
				)
			)
		)
		(duplicate_pad_numbers_are_jumpers no)
		(fp_line
			(start -0.508 -0.9398)
			(end -0.508 0.9398)
			(stroke
				(width 0.1524)
				(type default)
			)
			(layer "F.SilkS")
		)
		(fp_line
			(start 0.508 -0.9398)
			(end -0.508 -0.9398)
			(stroke
				(width 0.1524)
				(type default)
			)
			(layer "F.SilkS")
		)
		(fp_rect
			(start -0.508 0.9398)
			(end 0.508 -0.9398)
			(stroke
				(width 0)
				(type default)
			)
			(fill no)
			(layer "F.CrtYd")
		)
		(fp_rect
			(start -0.508 0.9398)
			(end 0.508 -0.9398)
			(stroke
				(width 0)
				(type default)
			)
			(fill no)
			(layer "F.Fab")
		)
		(pad "1" smd custom
			(at 0 -0.4445)
			(size 0.1397 0.1397)
			(layers "F.Cu" "F.Mask" "F.Paste")
			(net "P12V_IN")
			(options
				(clearance outline)
				(anchor circle)
			)
			(primitives
				(gr_poly
					(pts
						(arc
							(start -0.1778 -0.2794)
							(mid -0.249642 -0.249642)
							(end -0.2794 -0.1778)
						)
						(arc
							(start -0.2794 0.1778)
							(mid -0.249642 0.249642)
							(end -0.1778 0.2794)
						)
						(arc
							(start 0.1778 0.2794)
							(mid 0.249642 0.249642)
							(end 0.2794 0.1778)
						)
						(arc
							(start 0.2794 -0.1778)
							(mid 0.249642 -0.249642)
							(end 0.1778 -0.2794)
						)
					)
					(width 0)
					(fill yes)
				)
			)
		)
		(pad "2" smd custom
			(at 0 0.4445)
			(size 0.1397 0.1397)
			(layers "F.Cu" "F.Mask" "F.Paste")
			(net "GATE_FAN0")
			(options
				(clearance outline)
				(anchor circle)
			)
			(primitives
				(gr_poly
					(pts
						(arc
							(start -0.1778 -0.2794)
							(mid -0.249642 -0.249642)
							(end -0.2794 -0.1778)
						)
						(arc
							(start -0.2794 0.1778)
							(mid -0.249642 0.249642)
							(end -0.1778 0.2794)
						)
						(arc
							(start 0.1778 0.2794)
							(mid 0.249642 0.249642)
							(end 0.2794 0.1778)
						)
						(arc
							(start 0.2794 -0.1778)
							(mid 0.249642 -0.249642)
							(end 0.1778 -0.2794)
						)
					)
					(width 0)
					(fill yes)
				)
			)
		)
	)
	(footprint ""
		(layer "F.Cu")
		(at 333.6798 -13.2842 180)
		(property "Reference" "R777"
			(at 0 0 180)
			(layer "F.SilkS")
			(hide yes)
			(effects
				(font
					(size 1.27 1.27)
				)
			)
		)
		(property "Value" "0R2J-2-GP"
			(at 0.064008 -3.993896 180)
			(unlocked yes)
			(layer "F.Fab")
			(hide yes)
			(effects
				(font
					(size 1.016 1.016)
					(thickness 0.1524)
				)
			)
		)
		(property "Device Type" "R402H16"
			(at 0.064008 -5.517896 180)
			(unlocked yes)
			(layer "F.Fab")
			(hide yes)
			(effects
				(font
					(size 1.016 1.016)
					(thickness 0.1524)
				)
			)
		)
		(duplicate_pad_numbers_are_jumpers no)
		(fp_line
			(start 0.508 -0.9398)
			(end -0.508 -0.9398)
			(stroke
				(width 0.1524)
				(type default)
			)
			(layer "F.SilkS")
		)
		(fp_line
			(start -0.508 -0.9398)
			(end -0.508 0.9398)
			(stroke
				(width 0.1524)
				(type default)
			)
			(layer "F.SilkS")
		)
		(fp_rect
			(start -0.508 0.9398)
			(end 0.508 -0.9398)
			(stroke
				(width 0)
				(type default)
			)
			(fill no)
			(layer "F.CrtYd")
		)
		(fp_rect
			(start -0.508 0.9398)
			(end 0.508 -0.9398)
			(stroke
				(width 0)
				(type default)
			)
			(fill no)
			(layer "F.Fab")
		)
		(pad "1" smd custom
			(at 0 -0.4445 180)
			(size 0.1397 0.1397)
			(layers "F.Cu" "F.Mask" "F.Paste")
			(net "SW_HDD_G30")
			(options
				(clearance outline)
				(anchor circle)
			)
			(primitives
				(gr_poly
					(pts
						(arc
							(start -0.1778 -0.2794)
							(mid -0.249642 -0.249642)
							(end -0.2794 -0.1778)
						)
						(arc
							(start -0.2794 0.1778)
							(mid -0.249642 0.249642)
							(end -0.1778 0.2794)
						)
						(arc
							(start 0.1778 0.2794)
							(mid 0.249642 0.249642)
							(end 0.2794 0.1778)
						)
						(arc
							(start 0.2794 -0.1778)
							(mid 0.249642 -0.249642)
							(end 0.1778 -0.2794)
						)
					)
					(width 0)
					(fill yes)
				)
			)
		)
		(pad "2" smd custom
			(at 0 0.4445 180)
			(size 0.1397 0.1397)
			(layers "F.Cu" "F.Mask" "F.Paste")
			(net "SW_HDD_R30")
			(options
				(clearance outline)
				(anchor circle)
			)
			(primitives
				(gr_poly
					(pts
						(arc
							(start -0.1778 -0.2794)
							(mid -0.249642 -0.249642)
							(end -0.2794 -0.1778)
						)
						(arc
							(start -0.2794 0.1778)
							(mid -0.249642 0.249642)
							(end -0.1778 0.2794)
						)
						(arc
							(start 0.1778 0.2794)
							(mid 0.249642 0.249642)
							(end 0.2794 0.1778)
						)
						(arc
							(start 0.2794 -0.1778)
							(mid 0.249642 -0.249642)
							(end 0.1778 -0.2794)
						)
					)
					(width 0)
					(fill yes)
				)
			)
		)
	)
)
